(kicad_pcb
	(version 20260206)
	(generator "pcbnew")
	(generator_version "10.0")
	(general
		(thickness 1.6)
		(legacy_teardrops no)
	)
	(paper "A4")
	(title_block
		(title "panther-plus-userver — 13130-1b_20150205.brd")
		(comment 1 "Honey Badger (Wiwynn) / footprint 406 of 1509 (DIMM2), pads 198-204 of 210")
	)
	(layers
		(0 "F.Cu" signal "TOP")
		(4 "In1.Cu" signal "L2")
		(6 "In2.Cu" signal "L3")
		(8 "In3.Cu" signal "L4")
		(10 "In4.Cu" signal "L5")
		(12 "In5.Cu" signal "L6")
		(14 "In6.Cu" signal "L7")
		(16 "In7.Cu" signal "L8")
		(18 "In8.Cu" signal "L9")
		(20 "In9.Cu" signal "L10")
		(22 "In10.Cu" signal "L11")
		(2 "B.Cu" signal "BOTTOM")
		(9 "F.Adhes" user "F.Adhesive")
		(11 "B.Adhes" user "B.Adhesive")
		(13 "F.Paste" user "Package Geometry/Pastemask Top")
		(15 "B.Paste" user "Package Geometry/Pastemask Bottom")
		(5 "F.SilkS" user "Ref Des/Silkscreen Top")
		(7 "B.SilkS" user "Ref Des/Silkscreen Bottom")
		(1 "F.Mask" user "Board Geometry/Soldermask Top")
		(3 "B.Mask" user "Board Geometry/Soldermask Bottom")
		(17 "Dwgs.User" user "User.Drawings")
		(19 "Cmts.User" user "User.Comments")
		(21 "Eco1.User" user "User.Eco1")
		(23 "Eco2.User" user "User.Eco2")
		(25 "Edge.Cuts" user "Board Geometry/Outline")
		(27 "Margin" user)
		(31 "F.CrtYd" user "Package Geometry/Place Bound Top")
		(29 "B.CrtYd" user "Package Geometry/Place Bound Bottom")
		(35 "F.Fab" user "Ref Des/Assembly Top")
		(33 "B.Fab" user "Ref Des/Assembly Bottom")
	)
	(footprint ""
		(layer "F.Cu")
		(at 158.500064 -66.699892 180)
		(property "Reference" "DIMM2"
			(at 0 0 180)
			(layer "F.SilkS")
			(hide yes)
			(effects
				(font
					(size 1.27 1.27)
				)
			)
		)
		(property "Value" "DDR3-204P-174-COLAY-1-GP"
			(at -40.682164 -17.468088 180)
			(unlocked yes)
			(layer "F.Fab")
			(hide yes)
			(effects
				(font
					(size 1.016 1.016)
					(thickness 0.1524)
				)
			)
		)
		(property "Device Type" "AS0A626-H8SN-7H-COLAY-1"
			(at -40.682164 -18.992088 180)
			(unlocked yes)
			(layer "F.Fab")
			(hide yes)
			(effects
				(font
					(size 1.016 1.016)
					(thickness 0.1524)
				)
			)
		)
		(duplicate_pad_numbers_are_jumpers no)
		(pad "196" smd custom
			(at 29.249878 -4.106672 180)
			(size 0.1143 0.1143)
			(layers "F.Cu" "F.Mask" "F.Paste")
			(net "GND")
			(options
				(clearance outline)
				(anchor circle)
			)
			(primitives
				(gr_poly
					(pts
						(xy 0 0.9017) (xy -0.03175 0.89916) (xy -0.0635 0.889) (xy -0.09144 0.87376) (xy -0.11684 0.85344)
						(xy -0.13716 0.82804) (xy -0.1524 0.8001) (xy -0.16256 0.76835) (xy -0.1651 0.7366) (xy -0.1651 0.19685)
						(xy -0.17272 0.18923) (xy -0.17907 0.18034) (xy -0.18669 0.17145) (xy -0.19177 0.16256) (xy -0.19812 0.15367)
						(xy -0.20828 0.13335) (xy -0.21971 0.10287) (xy -0.22225 0.09271) (xy -0.22479 0.08128) (xy -0.22606 0.07112)
						(xy -0.2286 0.05969) (xy -0.2286 0.01651) (xy -0.22606 0.00508) (xy -0.22479 -0.00508) (xy -0.22225 -0.01651)
						(xy -0.21971 -0.02667) (xy -0.20828 -0.05715) (xy -0.19812 -0.07747) (xy -0.19177 -0.08636) (xy -0.18669 -0.09525)
						(xy -0.17907 -0.10414) (xy -0.17272 -0.11303) (xy -0.1651 -0.12065) (xy -0.1651 -0.7366) (xy -0.16256 -0.76835)
						(xy -0.1524 -0.8001) (xy -0.13716 -0.82804) (xy -0.11684 -0.85344) (xy -0.09144 -0.87376) (xy -0.0635 -0.889)
						(xy -0.03175 -0.89916) (xy 0 -0.9017) (xy 0.03175 -0.89916) (xy 0.0635 -0.889) (xy 0.09144 -0.87376)
						(xy 0.11684 -0.85344) (xy 0.13716 -0.82804) (xy 0.1524 -0.8001) (xy 0.16256 -0.76835) (xy 0.1651 -0.7366)
						(xy 0.1651 -0.11938) (xy 0.17272 -0.11176) (xy 0.19812 -0.0762) (xy 0.2032 -0.06604) (xy 0.20701 -0.05715)
						(xy 0.21209 -0.04699) (xy 0.2159 -0.03683) (xy 0.21844 -0.02667) (xy 0.22225 -0.01524) (xy 0.22352 -0.00508)
						(xy 0.22606 0.00508) (xy 0.22733 0.01651) (xy 0.22733 0.02667) (xy 0.2286 0.0381) (xy 0.22733 0.04953)
						(xy 0.22733 0.05969) (xy 0.22606 0.07112) (xy 0.22352 0.08128) (xy 0.22225 0.09144) (xy 0.21844 0.10287)
						(xy 0.2159 0.11303) (xy 0.21209 0.12319) (xy 0.20701 0.13335) (xy 0.2032 0.14224) (xy 0.19812 0.1524)
						(xy 0.17272 0.18796) (xy 0.1651 0.19558) (xy 0.1651 0.7366) (xy 0.16256 0.76835) (xy 0.1524 0.8001)
						(xy 0.13716 0.82804) (xy 0.11684 0.85344) (xy 0.09144 0.87376) (xy 0.0635 0.889) (xy 0.03175 0.89916)
					)
					(width 0)
					(fill yes)
				)
			)
		)
		(pad "197" smd custom
			(at 29.550106 4.106672 180)
			(size 0.1143 0.1143)
			(layers "F.Cu" "F.Mask" "F.Paste")
			(net "CHA_1_SA0")
			(options
				(clearance outline)
				(anchor circle)
			)
			(primitives
				(gr_poly
					(pts
						(xy 0 0.9017) (xy -0.03175 0.89916) (xy -0.0635 0.889) (xy -0.09144 0.87376) (xy -0.11684 0.85344)
						(xy -0.13716 0.82804) (xy -0.1524 0.8001) (xy -0.16256 0.76835) (xy -0.1651 0.7366) (xy -0.1651 -0.13462)
						(xy -0.17272 -0.14224) (xy -0.19812 -0.1778) (xy -0.2032 -0.18796) (xy -0.20701 -0.19685) (xy -0.21209 -0.20701)
						(xy -0.2159 -0.21717) (xy -0.21844 -0.22733) (xy -0.22225 -0.23876) (xy -0.22352 -0.24892) (xy -0.22606 -0.25908)
						(xy -0.22733 -0.27051) (xy -0.22733 -0.28067) (xy -0.2286 -0.2921) (xy -0.22733 -0.30353) (xy -0.22733 -0.31369)
						(xy -0.22606 -0.32512) (xy -0.22352 -0.33528) (xy -0.22225 -0.34544) (xy -0.21844 -0.35687) (xy -0.2159 -0.36703)
						(xy -0.21209 -0.37719) (xy -0.20701 -0.38735) (xy -0.2032 -0.39624) (xy -0.19812 -0.4064) (xy -0.17272 -0.44196)
						(xy -0.1651 -0.44958) (xy -0.1651 -0.7366) (xy -0.16256 -0.76835) (xy -0.1524 -0.8001) (xy -0.13716 -0.82804)
						(xy -0.11684 -0.85344) (xy -0.09144 -0.87376) (xy -0.0635 -0.889) (xy -0.03175 -0.89916) (xy 0 -0.9017)
						(xy 0.03175 -0.89916) (xy 0.0635 -0.889) (xy 0.09144 -0.87376) (xy 0.11684 -0.85344) (xy 0.13716 -0.82804)
						(xy 0.1524 -0.8001) (xy 0.16256 -0.76835) (xy 0.1651 -0.7366) (xy 0.1651 -0.44958) (xy 0.17272 -0.44196)
						(xy 0.19812 -0.4064) (xy 0.2032 -0.39624) (xy 0.20701 -0.38735) (xy 0.21209 -0.37719) (xy 0.2159 -0.36703)
						(xy 0.21844 -0.35687) (xy 0.22225 -0.34544) (xy 0.22352 -0.33528) (xy 0.22606 -0.32512) (xy 0.22733 -0.31369)
						(xy 0.22733 -0.30353) (xy 0.2286 -0.2921) (xy 0.22733 -0.28067) (xy 0.22733 -0.27051) (xy 0.22606 -0.25908)
						(xy 0.22352 -0.24892) (xy 0.22225 -0.23876) (xy 0.21844 -0.22733) (xy 0.2159 -0.21717) (xy 0.21209 -0.20701)
						(xy 0.20701 -0.19685) (xy 0.2032 -0.18796) (xy 0.19812 -0.1778) (xy 0.17272 -0.14224) (xy 0.1651 -0.13462)
						(xy 0.1651 0.7366) (xy 0.16256 0.76835) (xy 0.1524 0.8001) (xy 0.13716 0.82804) (xy 0.11684 0.85344)
						(xy 0.09144 0.87376) (xy 0.0635 0.889) (xy 0.03175 0.89916)
					)
					(width 0)
					(fill yes)
				)
			)
		)
		(pad "198" smd custom
			(at 29.85008 -4.106672 180)
			(size 0.1143 0.1143)
			(layers "F.Cu" "F.Mask" "F.Paste")
			(net "MEMORY_HOT_LV_R#")
			(options
				(clearance outline)
				(anchor circle)
			)
			(primitives
				(gr_poly
					(pts
						(xy 0 0.9017) (xy -0.03175 0.89916) (xy -0.0635 0.889) (xy -0.09144 0.87376) (xy -0.11684 0.85344)
						(xy -0.13716 0.82804) (xy -0.1524 0.8001) (xy -0.16256 0.76835) (xy -0.1651 0.7366) (xy -0.1651 0.44958)
						(xy -0.17272 0.44196) (xy -0.19812 0.4064) (xy -0.2032 0.39624) (xy -0.20701 0.38735) (xy -0.21209 0.37719)
						(xy -0.2159 0.36703) (xy -0.21844 0.35687) (xy -0.22225 0.34544) (xy -0.22352 0.33528) (xy -0.22606 0.32512)
						(xy -0.22733 0.31369) (xy -0.22733 0.30353) (xy -0.2286 0.2921) (xy -0.22733 0.28067) (xy -0.22733 0.27051)
						(xy -0.22606 0.25908) (xy -0.22352 0.24892) (xy -0.22225 0.23876) (xy -0.21844 0.22733) (xy -0.2159 0.21717)
						(xy -0.21209 0.20701) (xy -0.20701 0.19685) (xy -0.2032 0.18796) (xy -0.19812 0.1778) (xy -0.17272 0.14224)
						(xy -0.1651 0.13462) (xy -0.1651 -0.7366) (xy -0.16256 -0.76835) (xy -0.1524 -0.8001) (xy -0.13716 -0.82804)
						(xy -0.11684 -0.85344) (xy -0.09144 -0.87376) (xy -0.0635 -0.889) (xy -0.03175 -0.89916) (xy 0 -0.9017)
						(xy 0.03175 -0.89916) (xy 0.0635 -0.889) (xy 0.09144 -0.87376) (xy 0.11684 -0.85344) (xy 0.13716 -0.82804)
						(xy 0.1524 -0.8001) (xy 0.16256 -0.76835) (xy 0.1651 -0.7366) (xy 0.1651 0.13462) (xy 0.17272 0.14224)
						(xy 0.19812 0.1778) (xy 0.2032 0.18796) (xy 0.20701 0.19685) (xy 0.21209 0.20701) (xy 0.2159 0.21717)
						(xy 0.21844 0.22733) (xy 0.22225 0.23876) (xy 0.22352 0.24892) (xy 0.22606 0.25908) (xy 0.22733 0.27051)
						(xy 0.22733 0.28067) (xy 0.2286 0.2921) (xy 0.22733 0.30353) (xy 0.22733 0.31369) (xy 0.22606 0.32512)
						(xy 0.22352 0.33528) (xy 0.22225 0.34544) (xy 0.21844 0.35687) (xy 0.2159 0.36703) (xy 0.21209 0.37719)
						(xy 0.20701 0.38735) (xy 0.2032 0.39624) (xy 0.19812 0.4064) (xy 0.17272 0.44196) (xy 0.1651 0.44958)
						(xy 0.1651 0.7366) (xy 0.16256 0.76835) (xy 0.1524 0.8001) (xy 0.13716 0.82804) (xy 0.11684 0.85344)
						(xy 0.09144 0.87376) (xy 0.0635 0.889) (xy 0.03175 0.89916)
					)
					(width 0)
					(fill yes)
				)
			)
		)
		(pad "199" smd custom
			(at 30.150054 4.106672 180)
			(size 0.1143 0.1143)
			(layers "F.Cu" "F.Mask" "F.Paste")
			(net "P3V3_STBY")
			(options
				(clearance outline)
				(anchor circle)
			)
			(primitives
				(gr_poly
					(pts
						(xy 0 0.9017) (xy -0.03175 0.89916) (xy -0.0635 0.889) (xy -0.09144 0.87376) (xy -0.11684 0.85344)
						(xy -0.13716 0.82804) (xy -0.1524 0.8001) (xy -0.16256 0.76835) (xy -0.1651 0.7366) (xy -0.1651 0.11938)
						(xy -0.17272 0.11176) (xy -0.19812 0.0762) (xy -0.2032 0.06604) (xy -0.20701 0.05715) (xy -0.21209 0.04699)
						(xy -0.2159 0.03683) (xy -0.21844 0.02667) (xy -0.22225 0.01524) (xy -0.22352 0.00508) (xy -0.22606 -0.00508)
						(xy -0.22733 -0.01651) (xy -0.22733 -0.02667) (xy -0.2286 -0.0381) (xy -0.22733 -0.04953) (xy -0.22733 -0.05969)
						(xy -0.22606 -0.07112) (xy -0.22352 -0.08128) (xy -0.22225 -0.09144) (xy -0.21844 -0.10287) (xy -0.2159 -0.11303)
						(xy -0.21209 -0.12319) (xy -0.20701 -0.13335) (xy -0.2032 -0.14224) (xy -0.19812 -0.1524) (xy -0.17272 -0.18796)
						(xy -0.1651 -0.19558) (xy -0.1651 -0.7366) (xy -0.16256 -0.76835) (xy -0.1524 -0.8001) (xy -0.13716 -0.82804)
						(xy -0.11684 -0.85344) (xy -0.09144 -0.87376) (xy -0.0635 -0.889) (xy -0.03175 -0.89916) (xy 0 -0.9017)
						(xy 0.03175 -0.89916) (xy 0.0635 -0.889) (xy 0.09144 -0.87376) (xy 0.11684 -0.85344) (xy 0.13716 -0.82804)
						(xy 0.1524 -0.8001) (xy 0.16256 -0.76835) (xy 0.1651 -0.7366) (xy 0.1651 -0.19685) (xy 0.17272 -0.18923)
						(xy 0.17907 -0.18034) (xy 0.18669 -0.17145) (xy 0.19177 -0.16256) (xy 0.19812 -0.15367) (xy 0.20828 -0.13335)
						(xy 0.21971 -0.10287) (xy 0.22225 -0.09271) (xy 0.22479 -0.08128) (xy 0.22606 -0.07112) (xy 0.2286 -0.05969)
						(xy 0.2286 -0.01651) (xy 0.22606 -0.00508) (xy 0.22479 0.00508) (xy 0.22225 0.01651) (xy 0.21971 0.02667)
						(xy 0.20828 0.05715) (xy 0.19812 0.07747) (xy 0.19177 0.08636) (xy 0.18669 0.09525) (xy 0.17907 0.10414)
						(xy 0.17272 0.11303) (xy 0.1651 0.12065) (xy 0.1651 0.7366) (xy 0.16256 0.76835) (xy 0.1524 0.8001)
						(xy 0.13716 0.82804) (xy 0.11684 0.85344) (xy 0.09144 0.87376) (xy 0.0635 0.889) (xy 0.03175 0.89916)
					)
					(width 0)
					(fill yes)
				)
			)
		)
		(pad "200" smd custom
			(at 30.450028 -4.106672 180)
			(size 0.1143 0.1143)
			(layers "F.Cu" "F.Mask" "F.Paste")
			(net "SMB_M_A1_R_DATA")
			(options
				(clearance outline)
				(anchor circle)
			)
			(primitives
				(gr_poly
					(pts
						(xy 0 0.9017) (xy -0.03175 0.89916) (xy -0.0635 0.889) (xy -0.09144 0.87376) (xy -0.11684 0.85344)
						(xy -0.13716 0.82804) (xy -0.1524 0.8001) (xy -0.16256 0.76835) (xy -0.1651 0.7366) (xy -0.1651 0.19685)
						(xy -0.17272 0.18923) (xy -0.17907 0.18034) (xy -0.18669 0.17145) (xy -0.19177 0.16256) (xy -0.19812 0.15367)
						(xy -0.20828 0.13335) (xy -0.21971 0.10287) (xy -0.22225 0.09271) (xy -0.22479 0.08128) (xy -0.22606 0.07112)
						(xy -0.2286 0.05969) (xy -0.2286 0.01651) (xy -0.22606 0.00508) (xy -0.22479 -0.00508) (xy -0.22225 -0.01651)
						(xy -0.21971 -0.02667) (xy -0.20828 -0.05715) (xy -0.19812 -0.07747) (xy -0.19177 -0.08636) (xy -0.18669 -0.09525)
						(xy -0.17907 -0.10414) (xy -0.17272 -0.11303) (xy -0.1651 -0.12065) (xy -0.1651 -0.7366) (xy -0.16256 -0.76835)
						(xy -0.1524 -0.8001) (xy -0.13716 -0.82804) (xy -0.11684 -0.85344) (xy -0.09144 -0.87376) (xy -0.0635 -0.889)
						(xy -0.03175 -0.89916) (xy 0 -0.9017) (xy 0.03175 -0.89916) (xy 0.0635 -0.889) (xy 0.09144 -0.87376)
						(xy 0.11684 -0.85344) (xy 0.13716 -0.82804) (xy 0.1524 -0.8001) (xy 0.16256 -0.76835) (xy 0.1651 -0.7366)
						(xy 0.1651 -0.11938) (xy 0.17272 -0.11176) (xy 0.19812 -0.0762) (xy 0.2032 -0.06604) (xy 0.20701 -0.05715)
						(xy 0.21209 -0.04699) (xy 0.2159 -0.03683) (xy 0.21844 -0.02667) (xy 0.22225 -0.01524) (xy 0.22352 -0.00508)
						(xy 0.22606 0.00508) (xy 0.22733 0.01651) (xy 0.22733 0.02667) (xy 0.2286 0.0381) (xy 0.22733 0.04953)
						(xy 0.22733 0.05969) (xy 0.22606 0.07112) (xy 0.22352 0.08128) (xy 0.22225 0.09144) (xy 0.21844 0.10287)
						(xy 0.2159 0.11303) (xy 0.21209 0.12319) (xy 0.20701 0.13335) (xy 0.2032 0.14224) (xy 0.19812 0.1524)
						(xy 0.17272 0.18796) (xy 0.1651 0.19558) (xy 0.1651 0.7366) (xy 0.16256 0.76835) (xy 0.1524 0.8001)
						(xy 0.13716 0.82804) (xy 0.11684 0.85344) (xy 0.09144 0.87376) (xy 0.0635 0.889) (xy 0.03175 0.89916)
					)
					(width 0)
					(fill yes)
				)
			)
		)
		(pad "201" smd custom
			(at 30.750002 4.106672 180)
			(size 0.1143 0.1143)
			(layers "F.Cu" "F.Mask" "F.Paste")
			(net "CHA_1_SA1")
			(options
				(clearance outline)
				(anchor circle)
			)
			(primitives
				(gr_poly
					(pts
						(xy 0 0.9017) (xy -0.03175 0.89916) (xy -0.0635 0.889) (xy -0.09144 0.87376) (xy -0.11684 0.85344)
						(xy -0.13716 0.82804) (xy -0.1524 0.8001) (xy -0.16256 0.76835) (xy -0.1651 0.7366) (xy -0.1651 -0.13462)
						(xy -0.17272 -0.14224) (xy -0.19812 -0.1778) (xy -0.2032 -0.18796) (xy -0.20701 -0.19685) (xy -0.21209 -0.20701)
						(xy -0.2159 -0.21717) (xy -0.21844 -0.22733) (xy -0.22225 -0.23876) (xy -0.22352 -0.24892) (xy -0.22606 -0.25908)
						(xy -0.22733 -0.27051) (xy -0.22733 -0.28067) (xy -0.2286 -0.2921) (xy -0.22733 -0.30353) (xy -0.22733 -0.31369)
						(xy -0.22606 -0.32512) (xy -0.22352 -0.33528) (xy -0.22225 -0.34544) (xy -0.21844 -0.35687) (xy -0.2159 -0.36703)
						(xy -0.21209 -0.37719) (xy -0.20701 -0.38735) (xy -0.2032 -0.39624) (xy -0.19812 -0.4064) (xy -0.17272 -0.44196)
						(xy -0.1651 -0.44958) (xy -0.1651 -0.7366) (xy -0.16256 -0.76835) (xy -0.1524 -0.8001) (xy -0.13716 -0.82804)
						(xy -0.11684 -0.85344) (xy -0.09144 -0.87376) (xy -0.0635 -0.889) (xy -0.03175 -0.89916) (xy 0 -0.9017)
						(xy 0.03175 -0.89916) (xy 0.0635 -0.889) (xy 0.09144 -0.87376) (xy 0.11684 -0.85344) (xy 0.13716 -0.82804)
						(xy 0.1524 -0.8001) (xy 0.16256 -0.76835) (xy 0.1651 -0.7366) (xy 0.1651 -0.44958) (xy 0.17272 -0.44196)
						(xy 0.19812 -0.4064) (xy 0.2032 -0.39624) (xy 0.20701 -0.38735) (xy 0.21209 -0.37719) (xy 0.2159 -0.36703)
						(xy 0.21844 -0.35687) (xy 0.22225 -0.34544) (xy 0.22352 -0.33528) (xy 0.22606 -0.32512) (xy 0.22733 -0.31369)
						(xy 0.22733 -0.30353) (xy 0.2286 -0.2921) (xy 0.22733 -0.28067) (xy 0.22733 -0.27051) (xy 0.22606 -0.25908)
						(xy 0.22352 -0.24892) (xy 0.22225 -0.23876) (xy 0.21844 -0.22733) (xy 0.2159 -0.21717) (xy 0.21209 -0.20701)
						(xy 0.20701 -0.19685) (xy 0.2032 -0.18796) (xy 0.19812 -0.1778) (xy 0.17272 -0.14224) (xy 0.1651 -0.13462)
						(xy 0.1651 0.7366) (xy 0.16256 0.76835) (xy 0.1524 0.8001) (xy 0.13716 0.82804) (xy 0.11684 0.85344)
						(xy 0.09144 0.87376) (xy 0.0635 0.889) (xy 0.03175 0.89916)
					)
					(width 0)
					(fill yes)
				)
			)
		)
		(pad "202" smd custom
			(at 31.049976 -4.106672 180)
			(size 0.1143 0.1143)
			(layers "F.Cu" "F.Mask" "F.Paste")
			(net "SMB_M_A1_R_CLK")
			(options
				(clearance outline)
				(anchor circle)
			)
			(primitives
				(gr_poly
					(pts
						(xy 0 0.9017) (xy -0.03175 0.89916) (xy -0.0635 0.889) (xy -0.09144 0.87376) (xy -0.11684 0.85344)
						(xy -0.13716 0.82804) (xy -0.1524 0.8001) (xy -0.16256 0.76835) (xy -0.1651 0.7366) (xy -0.1651 0.44958)
						(xy -0.17272 0.44196) (xy -0.19812 0.4064) (xy -0.2032 0.39624) (xy -0.20701 0.38735) (xy -0.21209 0.37719)
						(xy -0.2159 0.36703) (xy -0.21844 0.35687) (xy -0.22225 0.34544) (xy -0.22352 0.33528) (xy -0.22606 0.32512)
						(xy -0.22733 0.31369) (xy -0.22733 0.30353) (xy -0.2286 0.2921) (xy -0.22733 0.28067) (xy -0.22733 0.27051)
						(xy -0.22606 0.25908) (xy -0.22352 0.24892) (xy -0.22225 0.23876) (xy -0.21844 0.22733) (xy -0.2159 0.21717)
						(xy -0.21209 0.20701) (xy -0.20701 0.19685) (xy -0.2032 0.18796) (xy -0.19812 0.1778) (xy -0.17272 0.14224)
						(xy -0.1651 0.13462) (xy -0.1651 -0.7366) (xy -0.16256 -0.76835) (xy -0.1524 -0.8001) (xy -0.13716 -0.82804)
						(xy -0.11684 -0.85344) (xy -0.09144 -0.87376) (xy -0.0635 -0.889) (xy -0.03175 -0.89916) (xy 0 -0.9017)
						(xy 0.03175 -0.89916) (xy 0.0635 -0.889) (xy 0.09144 -0.87376) (xy 0.11684 -0.85344) (xy 0.13716 -0.82804)
						(xy 0.1524 -0.8001) (xy 0.16256 -0.76835) (xy 0.1651 -0.7366) (xy 0.1651 0.13462) (xy 0.17272 0.14224)
						(xy 0.19812 0.1778) (xy 0.2032 0.18796) (xy 0.20701 0.19685) (xy 0.21209 0.20701) (xy 0.2159 0.21717)
						(xy 0.21844 0.22733) (xy 0.22225 0.23876) (xy 0.22352 0.24892) (xy 0.22606 0.25908) (xy 0.22733 0.27051)
						(xy 0.22733 0.28067) (xy 0.2286 0.2921) (xy 0.22733 0.30353) (xy 0.22733 0.31369) (xy 0.22606 0.32512)
						(xy 0.22352 0.33528) (xy 0.22225 0.34544) (xy 0.21844 0.35687) (xy 0.2159 0.36703) (xy 0.21209 0.37719)
						(xy 0.20701 0.38735) (xy 0.2032 0.39624) (xy 0.19812 0.4064) (xy 0.17272 0.44196) (xy 0.1651 0.44958)
						(xy 0.1651 0.7366) (xy 0.16256 0.76835) (xy 0.1524 0.8001) (xy 0.13716 0.82804) (xy 0.11684 0.85344)
						(xy 0.09144 0.87376) (xy 0.0635 0.889) (xy 0.03175 0.89916)
					)
					(width 0)
					(fill yes)
				)
			)
		)
	)
)
